FILE_TYPE = CONNECTIVITY;
{Allegro Design Entry HDL 17.2-2016 S081 (4005846) 1/11/2022}
"PAGE_NUMBER" = 314;
0"NC";
1"P5V_AUX_VCC\g";
2"P3V3_AUX\g";
3"P3V3_AUX\g";
4"P3V3_AUX\g";
5"P3V3_AUX\g";
6"GND\g";
7"GND\g";
8"GPU_NVS_PWR_BRAKE_R_N"CDS_PHYS_NET_NAME"GPU_NVS_PWR_BRAKE_R_N";
9"SMB_HOST_3V3AUX_PLD_SCL";
10"GPU_FPGA_EROT_RST_R_N"CDS_PHYS_NET_NAME"GPU_FPGA_EROT_RST_R_N";
11"SMB_HOST_3V3AUX_PLD_SDA";
12"PWRGD_P5V_AUX";
13"SMB_HOST_3V3AUX_SCL_R4";
14"SMB_HOST_3V3AUX_SDA_R4";
15"GPU_FPGA_THERM_OVERT_ISO_R_N"CDS_PHYS_NET_NAME"GPU_FPGA_THERM_OVERT_ISO_R_N";
16"GPU_FPGA_THERM_OVERT_ISO_N";
17"GPU_BASE_STBY_EN_R"CDS_PHYS_NET_NAME"GPU_BASE_STBY_EN_R";
18"GPU_NVS_PWR_BRAKE_N";
19"GPU_FPGA_EROT_RST_N";
20"GPU_BASE_STBY_EN";
21"GPU_BASE_HMC_READY_ISO";
22"GPU_HMC_PRSNT_ISO_N";
23"GPU_FPGA_BOOT_EN";
24"PWRGD_P5V_AUX_R1";
25"PWRGD_P5V_AUX_R2";
26"GPU_FPGA_EROT_RECOV_R_N"CDS_PHYS_NET_NAME"GPU_FPGA_EROT_RECOV_R_N";
27"GPU_FPGA_BOOT_EN_R"CDS_PHYS_NET_NAME"GPU_FPGA_BOOT_EN_R";
28"SMB_HOST_3V3AUX_PLD_SCL";
29"SMB_HOST_3V3AUX_PLD_SDA";
30"GPU_WP_HW_CTRL_R_N"CDS_PHYS_NET_NAME"GPU_WP_HW_CTRL_R_N";
31"GPU_PRSNT_N_ISO_R"CDS_PHYS_NET_NAME"GPU_PRSNT_N_ISO_R";
32"GPU_FPGA_EROT_FATALERR_ISO_R_N"CDS_PHYS_NET_NAME"GPU_FPGA_EROT_FATALERR_ISO_R_N";
33"GPU_FPGA_OVERT_ISO_R_N"CDS_PHYS_NET_NAME"GPU_FPGA_OVERT_ISO_R_N";
34"GPU_PRSNT_N_ISO_R"CDS_PHYS_NET_NAME"GPU_PRSNT_N_ISO_R";
35"BIC_MONITER_ISO_R"CDS_PHYS_NET_NAME"BIC_MONITER_ISO_R";
36"BMC_MONITER"CDS_PHYS_NET_NAME"BMC_MONITER";
37"SMB_BMC_GPU_EN";
38"SMB_BMC_SWB_EN"CDS_PHYS_NET_NAME"SMB_BMC_SWB_EN";
39"RST_BMC_FROM_SWB_ISO_R_N"CDS_PHYS_NET_NAME"RST_BMC_FROM_SWB_ISO_R_N";
40"FM_SWB_BIC_READY_ISO_R_N"CDS_PHYS_NET_NAME"FM_SWB_BIC_READY_ISO_R_N";
41"FM_GPU_HSC_EN_R"CDS_PHYS_NET_NAME"FM_GPU_HSC_EN_R";
42"FM_GPU_PWRGD_ISO_R"CDS_PHYS_NET_NAME"FM_GPU_PWRGD_ISO_R";
43"FM_GPU_PWR_EN"CDS_PHYS_NET_NAME"FM_GPU_PWR_EN";
44"FM_SWB_PWR_EN"CDS_PHYS_NET_NAME"FM_SWB_PWR_EN";
45"FM_PCH_PRSNT_N"CDS_PHYS_NET_NAME"FM_PCH_PRSNT_N";
46"FM_TPM_PRSNT_R_N"CDS_PHYS_NET_NAME"FM_TPM_PRSNT_R_N";
47"VIRTUAL_RESEAT_FPGA_R_N"CDS_PHYS_NET_NAME"VIRTUAL_RESEAT_FPGA_R_N";
48"FM_BMC_SUSACK_R_N"CDS_PHYS_NET_NAME"FM_BMC_SUSACK_R_N";
49"FM_FAN_PWR_EN"CDS_PHYS_NET_NAME"FM_FAN_PWR_EN";
50"FM_SWB_PWRGD_ISO_R"CDS_PHYS_NET_NAME"FM_SWB_PWRGD_ISO_R";
51"FM_SWB_PWRGD_ISO"CDS_PHYS_NET_NAME"FM_SWB_PWRGD_ISO";
52"RST_BMC_FROM_SWB_ISO_N";
53"FM_GPU_HSC_EN_R";
54"FM_OCP_V3_2_PWR_GOOD";
55"FM_SWB_BIC_READY_ISO_N"CDS_PHYS_NET_NAME"FM_SWB_BIC_READY_ISO_N";
56"FM_GPU_PWR_EN"CDS_PHYS_NET_NAME"FM_GPU_PWR_EN";
57"GPU_FPGA_READY_ISO";
58"FM_OCP_SFF_PWR_GOOD";
59"FM_GPU_PWRGD_ISO";
60"RST_BMC_FROM_SWB_ISO_R_N"CDS_PHYS_NET_NAME"RST_BMC_FROM_SWB_ISO_R_N";
61"FM_GPU_HSC_EN"CDS_PHYS_NET_NAME"FM_GPU_HSC_EN";
62"GPU_FPGA_READY_ISO_R"CDS_PHYS_NET_NAME"GPU_FPGA_READY_ISO_R";
63"FM_SWB_PWRGD_ISO_R"CDS_PHYS_NET_NAME"FM_SWB_PWRGD_ISO_R";
64"FM_SWB_BIC_READY_ISO_R_N"CDS_PHYS_NET_NAME"FM_SWB_BIC_READY_ISO_R_N";
65"FM_OCP_SFF_PWR_GOOD_R"CDS_PHYS_NET_NAME"FM_OCP_SFF_PWR_GOOD_R";
66"FM_GPU_PWRGD_ISO_R"CDS_PHYS_NET_NAME"FM_GPU_PWRGD_ISO_R";
67"FM_GPU_PWR_EN_R"CDS_PHYS_NET_NAME"FM_GPU_PWR_EN_R";
68"IRQ_HSC_FAULT_R1_N"CDS_PHYS_NET_NAME"IRQ_HSC_FAULT_R1_N";
69"FM_OCP_V3_2_PWR_GOOD_R"CDS_PHYS_NET_NAME"FM_OCP_V3_2_PWR_GOOD_R";
70"JTAG_BMC_SW_OE";
71"OCP_SFF_CLK_OE_R_N";
72"FM_TPM_PRSNT_R_N"CDS_PHYS_NET_NAME"FM_TPM_PRSNT_R_N";
73"VIRTUAL_RESEAT_FPGA_R_N"CDS_PHYS_NET_NAME"VIRTUAL_RESEAT_FPGA_R_N";
74"FM_BMC_SUSACK_R_N"CDS_PHYS_NET_NAME"FM_BMC_SUSACK_R_N";
75"BMC_MONITER"CDS_PHYS_NET_NAME"BMC_MONITER";
76"BIC_MONITER_ISO"CDS_PHYS_NET_NAME"BIC_MONITER_ISO";
77"FM_SWB_PWR_EN"CDS_PHYS_NET_NAME"FM_SWB_PWR_EN";
78"NC_FPGA_PT43D"CDS_PHYS_NET_NAME"NC_FPGA_PT43D";
79"NC_FPGA_PT44A"CDS_PHYS_NET_NAME"NC_FPGA_PT44A";
80"NC_FPGA_PT43C"CDS_PHYS_NET_NAME"NC_FPGA_PT43C";
81"NC_FPGA_PT42D"CDS_PHYS_NET_NAME"NC_FPGA_PT42D";
82"RST_SRST_PLD_BMC_R_N"CDS_PHYS_NET_NAME"RST_SRST_PLD_BMC_R_N";
83"NC_FPGA_PT43A"CDS_PHYS_NET_NAME"NC_FPGA_PT43A";
84"NC_FPGA_PT43B"CDS_PHYS_NET_NAME"NC_FPGA_PT43B";
85"NC_FPGA_PT44B"CDS_PHYS_NET_NAME"NC_FPGA_PT44B";
86"SMB_1_PLD_3V3AUX_SCL_R1"CDS_PHYS_NET_NAME"SMB_1_PLD_3V3AUX_SCL_R1";
87"P12V_HSC_TEMP_ALERT_R_N"CDS_PHYS_NET_NAME"P12V_HSC_TEMP_ALERT_R_N";
88"P12V_HSC_T_CRIT_R_N"CDS_PHYS_NET_NAME"P12V_HSC_T_CRIT_R_N";
89"SGPIO_OCP_SFF_LD_N"CDS_PHYS_NET_NAME"SGPIO_OCP_SFF_LD_N";
90"SGPIO_OCP_V3_2_DATAOUT"CDS_PHYS_NET_NAME"SGPIO_OCP_V3_2_DATAOUT";
91"SGPIO_OCP_V3_2_CLK"CDS_PHYS_NET_NAME"SGPIO_OCP_V3_2_CLK";
92"PU_MAIN_FPGA_CONFIG_DONE"CDS_PHYS_NET_NAME"PU_MAIN_FPGA_CONFIG_DONE";
93"JTAG_BMC_SW_PLD_OE";
94"NC_FPGA_PT41D"CDS_PHYS_NET_NAME"NC_FPGA_PT41D";
95"SGPIO_OCP_V3_2_LD_N"CDS_PHYS_NET_NAME"SGPIO_OCP_V3_2_LD_N";
96"SGPIO_OCP_V3_2_DATAIN"CDS_PHYS_NET_NAME"SGPIO_OCP_V3_2_DATAIN";
97"GPU_FPGA_READY_ISO_R"CDS_PHYS_NET_NAME"GPU_FPGA_READY_ISO_R";
98"FM_NCSI_OCP_V3_2_R_OE"CDS_PHYS_NET_NAME"FM_NCSI_OCP_V3_2_R_OE";
99"SGPIO_BMC_DIN_R"CDS_PHYS_NET_NAME"SGPIO_BMC_DIN_R";
100"SGPIO_BMC_LD_N"CDS_PHYS_NET_NAME"SGPIO_BMC_LD_N";
101"SGPIO_BMC_CLK"CDS_PHYS_NET_NAME"SGPIO_BMC_CLK";
102"SGPIO_BMC_DOUT"CDS_PHYS_NET_NAME"SGPIO_BMC_DOUT";
103"SGPIO_DEBUG_PLD_DIN"CDS_PHYS_NET_NAME"SGPIO_DEBUG_PLD_DIN";
104"SGPIO_DEBUG_PLD_LD_N"CDS_PHYS_NET_NAME"SGPIO_DEBUG_PLD_LD_N";
105"SGPIO_OCP_SFF_DATAOUT"CDS_PHYS_NET_NAME"SGPIO_OCP_SFF_DATAOUT";
106"SGPIO_OCP_SFF_CLK"CDS_PHYS_NET_NAME"SGPIO_OCP_SFF_CLK";
107"SGPIO_OCP_SFF_DATAIN"CDS_PHYS_NET_NAME"SGPIO_OCP_SFF_DATAIN";
108"SGPIO_DEBUG_PLD_DOUT"CDS_PHYS_NET_NAME"SGPIO_DEBUG_PLD_DOUT";
109"SGPIO_DEBUG_PLD_CLK"CDS_PHYS_NET_NAME"SGPIO_DEBUG_PLD_CLK";
110"PWRGD_PVPP_HBM_CPU1"CDS_PHYS_NET_NAME"PWRGD_PVPP_HBM_CPU1";
111"PWRGD_P3V3"CDS_PHYS_NET_NAME"PWRGD_P3V3";
112"PWRGD_P5V_AUX_R2"CDS_PHYS_NET_NAME"PWRGD_P5V_AUX_R2";
113"SMB_1_PLD_3V3AUX_SDA_R1"CDS_PHYS_NET_NAME"SMB_1_PLD_3V3AUX_SDA_R1";
114"JTAG_BMC_SW_PLD_OE";
115"FM_TPM_PRSNT_N"CDS_PHYS_NET_NAME"FM_TPM_PRSNT_N";
116"OCP_SFF_CLK_OE_N";
117"VIRTUAL_RESEAT_FPGA_N"CDS_PHYS_NET_NAME"VIRTUAL_RESEAT_FPGA_N";
118"BMC_MONITER_R"CDS_PHYS_NET_NAME"BMC_MONITER_R";
119"BIC_MONITER_ISO_R"CDS_PHYS_NET_NAME"BIC_MONITER_ISO_R";
120"FM_SUSACK_N"CDS_PHYS_NET_NAME"FM_SUSACK_N";
121"FM_SWB_PWR_EN_R"CDS_PHYS_NET_NAME"FM_SWB_PWR_EN_R";
122"IRQ_HSC_FAULT_N"CDS_PHYS_NET_NAME"IRQ_HSC_FAULT_N";
123"PWRGD_PVCCFA_EHV_FIVRA_CPU0"CDS_PHYS_NET_NAME"PWRGD_PVCCFA_EHV_FIVRA_CPU0";
124"PWRGD_PVCCD_HV_CPU0"CDS_PHYS_NET_NAME"PWRGD_PVCCD_HV_CPU0";
125"PWRGD_P3V3_AUX_PLD"CDS_PHYS_NET_NAME"PWRGD_P3V3_AUX_PLD";
126"PWRGD_PVCCIN_CPU0"CDS_PHYS_NET_NAME"PWRGD_PVCCIN_CPU0";
127"PWRGD_PVNN_MAIN_CPU0"CDS_PHYS_NET_NAME"PWRGD_PVNN_MAIN_CPU0";
128"PWRGD_PVNN_PCH_AUX"CDS_PHYS_NET_NAME"PWRGD_PVNN_PCH_AUX";
129"PWRGD_PVNN_MAIN_CPU1"CDS_PHYS_NET_NAME"PWRGD_PVNN_MAIN_CPU1";
130"PWRGD_PVPP_HBM_CPU0"CDS_PHYS_NET_NAME"PWRGD_PVPP_HBM_CPU0";
131"GPU_BASE_HMC_READY_ISO_R"CDS_PHYS_NET_NAME"GPU_BASE_HMC_READY_ISO_R";
132"GPU_HMC_PRSNT_ISO_R_N"CDS_PHYS_NET_NAME"GPU_HMC_PRSNT_ISO_R_N";
133"GPU_FPGA_OVERT_ISO_N";
134"GPU_FPGA_EROT_RECOV_N";
135"GPU_BASE_HMC_READY_ISO_R"CDS_PHYS_NET_NAME"GPU_BASE_HMC_READY_ISO_R";
136"RST_SRST_PLD_BMC_R_N"CDS_PHYS_NET_NAME"RST_SRST_PLD_BMC_R_N";
137"GPU_FPGA_EROT_FATALERR_ISO_N";
138"GPU_PRSNT_N_ISO";
139"GPU_WP_HW_CTRL_N";
140"GPU_HMC_PRSNT_ISO_R_N"CDS_PHYS_NET_NAME"GPU_HMC_PRSNT_ISO_R_N";
141"GPU_FPGA_BOOT_EN_R"CDS_PHYS_NET_NAME"GPU_FPGA_BOOT_EN_R";
142"GPU_FPGA_EROT_RECOV_R_N"CDS_PHYS_NET_NAME"GPU_FPGA_EROT_RECOV_R_N";
143"GPU_WP_HW_CTRL_R_N"CDS_PHYS_NET_NAME"GPU_WP_HW_CTRL_R_N";
144"RST_SRST_PLD_BMC_N"CDS_PHYS_NET_NAME"RST_SRST_PLD_BMC_N";
145"GPU_FPGA_EROT_FATALERR_ISO_R_N"CDS_PHYS_NET_NAME"GPU_FPGA_EROT_FATALERR_ISO_R_N";
146"GPU_FPGA_OVERT_ISO_R_N"CDS_PHYS_NET_NAME"GPU_FPGA_OVERT_ISO_R_N";
147"GPU_NVS_PWR_BRAKE_R_N"CDS_PHYS_NET_NAME"GPU_NVS_PWR_BRAKE_R_N";
148"GPU_FPGA_THERM_OVERT_ISO_R_N"CDS_PHYS_NET_NAME"GPU_FPGA_THERM_OVERT_ISO_R_N";
149"FM_S3M_CPU0_CPLD_CRC_ERROR"CDS_PHYS_NET_NAME"FM_S3M_CPU0_CPLD_CRC_ERROR";
150"FM_OCP_SFF_PWR_GOOD_R"CDS_PHYS_NET_NAME"FM_OCP_SFF_PWR_GOOD_R";
151"FM_SLP_SUS_RSM_RST_N"CDS_PHYS_NET_NAME"FM_SLP_SUS_RSM_RST_N";
152"PU_RST_DEDI_BUSY_PLD_N"CDS_PHYS_NET_NAME"PU_RST_DEDI_BUSY_PLD_N";
153"GPU_FPGA_EROT_RST_R_N"CDS_PHYS_NET_NAME"GPU_FPGA_EROT_RST_R_N";
154"GPU_BASE_STBY_EN_R"CDS_PHYS_NET_NAME"GPU_BASE_STBY_EN_R";
155"IRQ_SML1_PMBUS_PLD_ALERT_N"CDS_PHYS_NET_NAME"IRQ_SML1_PMBUS_PLD_ALERT_N";
156"IRQ_SML0_ALERT_R_N"CDS_PHYS_NET_NAME"IRQ_SML0_ALERT_R_N";
157"IRQ_SML1_PMBUS_BMC_ALERT_N"CDS_PHYS_NET_NAME"IRQ_SML1_PMBUS_BMC_ALERT_N";
158"OCP_SFF_CLK_OE_R_N";
159"FM_S3M_CPU1_CPLD_CRC_ERROR"CDS_PHYS_NET_NAME"FM_S3M_CPU1_CPLD_CRC_ERROR";
160"FM_OCP_V3_2_PWR_GOOD_R"CDS_PHYS_NET_NAME"FM_OCP_V3_2_PWR_GOOD_R";
161"OCP_SFF_AUX_PWR_PLD_EN"CDS_PHYS_NET_NAME"OCP_SFF_AUX_PWR_EN";
162"IRQ_HSC_FAULT_R1_N"CDS_PHYS_NET_NAME"IRQ_HSC_FAULT_R1_N";
163"FM_PECI_MUX_SEL_N"CDS_PHYS_NET_NAME"FM_PECI_MUX_SEL_N";
164"OCP_V3_2_AUX_PWR_PLD_EN"CDS_PHYS_NET_NAME"OCP_V3_2_AUX_PWR_EN";
%"Q_RES"
"1","(2725,-1400)","0","pure_quanta","I106";
;
PART_NUMBER"CS03322FB03"
VALUE"33.2"
MATERIAL"CHIP"
LOCATION"R2939"
CDS_LIB"pure_quanta"
TOLERANCE"1%"
PACK_TYPE"0402LF"
WATTAGE"1/16W"
$SEC"1"
CDS_SEC"1";
"B"
$PN"2"61;
"A"
$PN"1"53;
%"Q_RES"
"1","(2725,-1225)","0","pure_quanta","I107";
;
PART_NUMBER"CS03322FB03"
MATERIAL"CHIP"
VALUE"33.2"
LOCATION"R2847"
CDS_LIB"pure_quanta"
TOLERANCE"1%"
PACK_TYPE"0402LF"
WATTAGE"1/16W"
$SEC"1"
CDS_SEC"1";
"B"
$PN"2"60;
"A"
$PN"1"52;
%"Q_RES"
"1","(2725,-1050)","0","pure_quanta","I108";
;
PART_NUMBER"CS03322FB03"
VALUE"33.2"
MATERIAL"CHIP"
LOCATION"R3324"
TOLERANCE"1%"
PACK_TYPE"0402LF"
WATTAGE"1/16W"
CDS_LIB"pure_quanta"
$SEC"1"
CDS_SEC"1";
"B"
$PN"2"62;
"A"
$PN"1"57;
%"Q_RES"
"1","(2725,-925)","0","pure_quanta","I109";
;
PART_NUMBER"CS03322FB03"
VALUE"33.2"
MATERIAL"CHIP"
LOCATION"R1606"
CDS_LIB"pure_quanta"
WATTAGE"1/16W"
PACK_TYPE"0402LF"
TOLERANCE"1%"
$SEC"1"
CDS_SEC"1";
"B"
$PN"2"65;
"A"
$PN"1"58;
%"Q_RES"
"1","(2725,-775)","0","pure_quanta","I110";
;
PART_NUMBER"CS03322FB03"
VALUE"33.2"
MATERIAL"CHIP"
LOCATION"R3230"
CDS_LIB"pure_quanta"
WATTAGE"1/16W"
PACK_TYPE"0402LF"
TOLERANCE"1%"
$SEC"1"
CDS_SEC"1";
"B"
$PN"2"69;
"A"
$PN"1"54;
%"Q_RES"
"1","(2725,-650)","0","pure_quanta","I111";
;
PART_NUMBER"CS03322FB03"
VALUE"33.2"
MATERIAL"CHIP"
LOCATION"R3043"
CDS_LIB"pure_quanta"
WATTAGE"1/16W"
PACK_TYPE"0402LF"
TOLERANCE"1%"
$SEC"1"
CDS_SEC"1";
"B"
$PN"2"68;
"A"
$PN"1"122;
%"Q_RES"
"1","(2725,-525)","0","pure_quanta","I112";
;
PART_NUMBER"CS03322FB03"
VALUE"33.2"
MATERIAL"CHIP"
LOCATION"R2844"
TOLERANCE"1%"
PACK_TYPE"0402LF"
WATTAGE"1/16W"
CDS_LIB"pure_quanta"
$SEC"1"
CDS_SEC"1";
"B"
$PN"2"64;
"A"
$PN"1"55;
%"Q_RES"
"1","(2725,-400)","0","pure_quanta","I113";
;
PART_NUMBER"CS03322FB03"
VALUE"33.2"
MATERIAL"CHIP"
LOCATION"R2664"
CDS_LIB"pure_quanta"
WATTAGE"1/16W"
PACK_TYPE"0402LF"
TOLERANCE"1%"
$SEC"1"
CDS_SEC"1";
"B"
$PN"2"66;
"A"
$PN"1"59;
%"Q_RES"
"1","(2725,-275)","0","pure_quanta","I114";
;
PART_NUMBER"CS03322FB03"
MATERIAL"CHIP"
VALUE"33.2"
LOCATION"R2663"
CDS_LIB"pure_quanta"
WATTAGE"1/16W"
PACK_TYPE"0402LF"
TOLERANCE"1%"
$SEC"1"
CDS_SEC"1";
"B"
$PN"2"63;
"A"
$PN"1"51;
%"Q_RES"
"1","(2725,-150)","0","pure_quanta","I115";
;
PART_NUMBER"CS03322FB03"
VALUE"33.2"
MATERIAL"CHIP"
LOCATION"R2662"
CDS_LIB"pure_quanta"
TOLERANCE"1%"
PACK_TYPE"0402LF"
WATTAGE"1/16W"
$SEC"1"
CDS_SEC"1";
"B"
$PN"2"67;
"A"
$PN"1"56;
%"Q_RES"
"1","(2725,125)","0","pure_quanta","I134";
;
PART_NUMBER"CS03322FB03"
VALUE"33.2"
MATERIAL"CHIP"
LOCATION"R2846"
TOLERANCE"1%"
PACK_TYPE"0402LF"
WATTAGE"1/16W"
CDS_LIB"pure_quanta"
$SEC"1"
CDS_SEC"1";
"B"
$PN"2"119;
"A"
$PN"1"76;
%"Q_RES"
"1","(2725,-25)","0","pure_quanta","I135";
;
PART_NUMBER"CS03322FB03"
MATERIAL"CHIP"
VALUE"33.2"
LOCATION"R2661"
WATTAGE"1/16W"
PACK_TYPE"0402LF"
TOLERANCE"1%"
CDS_LIB"pure_quanta"
$SEC"1"
CDS_SEC"1";
"B"
$PN"2"121;
"A"
$PN"1"77;
%"Q_RES"
"1","(2725,300)","0","pure_quanta","I136";
;
PART_NUMBER"CS03322FB03"
VALUE"33.2"
MATERIAL"CHIP"
LOCATION"R2845"
TOLERANCE"1%"
PACK_TYPE"0402LF"
WATTAGE"1/16W"
CDS_LIB"pure_quanta"
$SEC"1"
CDS_SEC"1";
"B"
$PN"2"118;
"A"
$PN"1"75;
%"Q_RES"
"1","(2725,450)","0","pure_quanta","I137";
;
PART_NUMBER"CS00002JB13"
MATERIAL"EMPTY"
TOLERANCE"5%"
VALUE"0"
$LOCATION"R2071"
CDS_LIB"pure_quanta"
PACK_TYPE"0402LF"
WATTAGE"1/16W"
CDS_LOCATION"R2071"
$SEC"1"
CDS_SEC"1";
"B"
$PN"2"120;
"A"
$PN"1"74;
%"Q_RES"
"1","(2725,575)","0","pure_quanta","I138";
;
PART_NUMBER"CS00002JB13"
MATERIAL"CHIP"
TOLERANCE"5%"
VALUE"0"
$LOCATION"R1853"
WATTAGE"1/16W"
PACK_TYPE"0402LF"
CDS_LIB"pure_quanta"
CDS_LOCATION"R1853"
$SEC"1"
CDS_SEC"1";
"B"
$PN"2"117;
"A"
$PN"1"73;
%"Q_RES"
"1","(2725,700)","0","pure_quanta","I139";
;
PART_NUMBER"CS00002JB13"
MATERIAL"CHIP"
VALUE"0"
TOLERANCE"5%"
$LOCATION"R1547"
CDS_LIB"pure_quanta"
WATTAGE"1/16W"
PACK_TYPE"0402LF"
CDS_LOCATION"R1547"
$SEC"1"
CDS_SEC"1";
"B"
$PN"2"115;
"A"
$PN"1"72;
%"Q_RES"
"1","(-2275,-1675)","0","pure_quanta","I14";
;
PART_NUMBER"CS00002JB13"
VALUE"0"
TOLERANCE"5%"
MATERIAL"CHIP"
$LOCATION"R4697"
WATTAGE"1/16W"
PACK_TYPE"0402LF"
CDS_LIB"pure_quanta"
CDS_LOCATION"R4697"
$SEC"1"
CDS_SEC"1";
"B"
$PN"2"144;
"A"
$PN"1"136;
%"Q_RES"
"1","(2725,950)","0","pure_quanta","I140";
;
PART_NUMBER"CS11002FB07"
VALUE"100"
WATTAGE"1/16W"
MATERIAL"CHIP"
TOLERANCE"1%"
PACK_TYPE"0402LF"
$LOCATION"R4625"
CDS_LIB"pure_quanta"
CDS_LOCATION"R4625"
$SEC"1"
CDS_SEC"1";
"B"
$PN"2"114;
"A"
$PN"1"70;
%"Q_RES"
"1","(2725,825)","0","pure_quanta","I141";
;
PART_NUMBER"CS03322FB03"
MATERIAL"CHIP"
VALUE"33.2"
$LOCATION"R4495"
CDS_LIB"pure_quanta"
TOLERANCE"1%"
PACK_TYPE"0402LF"
WATTAGE"1/16W"
CDS_LOCATION"R4495"
$SEC"1"
CDS_SEC"1";
"B"
$PN"2"116;
"A"
$PN"1"71;
%"Q_RES"
"1","(-2225,-1375)","0","pure_quanta","I15";
;
PART_NUMBER"CS03322FB03"
VALUE"33.2"
MATERIAL"CHIP"
LOCATION"R3486"
TOLERANCE"1%"
PACK_TYPE"0402LF"
WATTAGE"1/16W"
CDS_LIB"pure_quanta"
$SEC"1"
CDS_SEC"1";
"B"
$PN"2"34;
"A"
$PN"1"138;
%"Q_RES"
"1","(-2225,-1500)","0","pure_quanta","I16";
;
PART_NUMBER"CS03322FB03"
MATERIAL"CHIP"
VALUE"33.2"
LOCATION"R3505"
TOLERANCE"1%"
PACK_TYPE"0402LF"
WATTAGE"1/16W"
CDS_LIB"pure_quanta"
$SEC"1"
CDS_SEC"1";
"B"
$PN"2"145;
"A"
$PN"1"137;
%"Q_RES"
"1","(-2225,-1125)","0","pure_quanta","I17";
;
PART_NUMBER"CS03322FB03"
VALUE"33.2"
MATERIAL"CHIP"
LOCATION"R3484"
CDS_LIB"pure_quanta"
WATTAGE"1/16W"
PACK_TYPE"0402LF"
TOLERANCE"1%"
$SEC"1"
CDS_SEC"1";
"B"
$PN"2"146;
"A"
$PN"1"133;
%"Q_RES"
"2","(2750,4150)","2","pure_quanta","I178";
;
PART_NUMBER"CS24702FB06"
WATTAGE"1/16W"
MATERIAL"EMPTY"
PACK_TYPE"0402LF"
VALUE"4.7K"
TOLERANCE"1%"
$LOCATION"R1467"
CDS_LIB"pure_quanta"
CDS_LOCATION"R1467"
$SEC"1"
CDS_SEC"1";
"A"
$PN"1"2;
"B"
$PN"2"86;
%"Q_RES"
"2","(2825,4150)","0","pure_quanta","I179";
;
PART_NUMBER"CS24702FB06"
PACK_TYPE"0402LF"
MATERIAL"EMPTY"
WATTAGE"1/16W"
VALUE"4.7K"
TOLERANCE"1%"
$LOCATION"R1551"
CDS_LIB"pure_quanta"
CDS_LOCATION"R1551"
$SEC"1"
CDS_SEC"1";
"A"
$PN"1"2;
"B"
$PN"2"113;
%"Q_RES"
"1","(-2225,-1250)","0","pure_quanta","I18";
;
PART_NUMBER"CS03322FB03"
VALUE"33.2"
MATERIAL"CHIP"
LOCATION"R3485"
CDS_LIB"pure_quanta"
WATTAGE"1/16W"
PACK_TYPE"0402LF"
TOLERANCE"1%"
$SEC"1"
CDS_SEC"1";
"B"
$PN"2"143;
"A"
$PN"1"139;
%"UNIVERSAL_POWER"
"1","(2825,4475)","0","logical_power","I180";
;
HDL_POWER"P3V3_AUX"
CDS_LIB"logical_power";
"A"2;
%"LCMXO3LF9400C5BG484C"
"3","(800,2675)","0","pure_quanta","I188";
;
PART_NUMBER"AJ094000T08"
MATERIAL"IC"
VALUE"LCMXO3LF-9400C-5BG484C"
PART_TYPE"SMLF"
$LOCATION"U249"
CDS_LIB"pure_quanta"
NEEDS_NO_SIZE"TRUE"
CDS_LMAN_SYM_OUTLINE"-900,1250,900,-1250"
CDS_LOCATION"U249"
$SEC"3"
CDS_SEC"3";
"PT43D"
$PN"C20"78;
"PT43C"
$PN"C19"80;
"PT42D"
$PN"G15"81;
"PT42C"
$PN"F15"82;
"PT42B"
$PN"B20"88;
"PT42A"
$PN"A19"87;
"PT41D"
$PN"D18"94;
"PT41C"
$PN"C18"93;
"PT40D"
$PN"D17"95;
"PT40C"
$PN"E16"96;
"PT40B"
$PN"B18"91;
"PT40A"
$PN"A17"90;
"PT39D"
$PN"D16"89;
"PT39C"
$PN"C17"107;
"PT39B"
$PN"B17"106;
"PT39A"
$PN"A16"105;
"PT38D"
$PN"D15"104;
"PT38C"
$PN"C15"103;
"PT38B"
$PN"B15"109;
"PT38A"
$PN"A15"108;
"PT30D"
$PN"D14"101;
"PT30C"
$PN"C14"102;
"PT30B"
$PN"B14"98;
"PT30A"
$PN"A14"110;
"PT29D"
$PN"D13"130;
"PT29C"
$PN"C13"129;
"PT29B"
$PN"B13"128;
"PT29A"
$PN"A13"127;
"PT28D"
$PN"F13"126;
"PT28C"
$PN"E13"123;
"PT27B"
$PN"E12"111;
"PT27A"
$PN"D12"112;
"PT24D"
$PN"D11"32;
"PT24C"
$PN"E11"31;
"PT24B"
$PN"A11"30;
"PT24A"
$PN"B11"33;
"PT23D"
$PN"F11"26;
"PT23C"
$PN"G11"27;
"PT21D"
$PN"G9"154;
"PT21C"
$PN"F9"153;
"PT21B"
$PN"A9"147;
"PT21A"
$PN"B9"148;
"PT20D"
$PN"D9"152;
"PT20C"
$PN"C9"151;
"PT20B"
$PN"A8"155;
"PT20A"
$PN"B8"156;
"PT14D"
$PN"D7"159;
"PT14C"
$PN"C6"149;
"PT14B"
$PN"A7"150;
"PT14A"
$PN"B6"160;
"PT13D"
$PN"E7"161;
"PT13C"
$PN"D6"164;
"PT13B"
$PN"A6"163;
"PT13A"
$PN"B5"162;
"PT12D"
$PN"C5"48;
"PT12C"
$PN"D5"47;
"PT12B"
$PN"A5"46;
"PT12A"
$PN"B4"45;
"PT10D"
$PN"C4"36;
"PT10C"
$PN"C3"35;
"PT10B"
$PN"A3"41;
"PT10A"
$PN"B2"49;
"PT11D"
$PN"G8"37;
"PT11C"
$PN"F8"39;
"PT22B"
$PN"E10"132;
"PT22A"
$PN"F10"131;
"PT11B"
$PN"A4"38;
"PT11A"
$PN"B3"40;
"PT15A"
$PN"C8"158;
"PT9A||L_GPLLT"
$PN"B1"44;
"PT9C"
$PN"E6"50;
"PT9B||L_GPLLC"
$PN"A2"43;
"PT9D"
$PN"F7"42;
"PT15B"
$PN"D8"157;
"PT23A||PCLKT0_1"
$PN"B10"29;
"PT23B||PCLKC0_1"
$PN"A10"28;
"PT44A||R_GPLLT"
$PN"A21"79;
"PT44B||R_GPLLC"
$PN"B22"85;
"PT27C||SCL||PCLKT0_0"
$PN"B12"86;
"PT27D||SDA||PCLKC0_0"
$PN"A12"113;
"PT28A"
$PN"G12"125;
"PT28B"
$PN"F12"124;
"PT31A"
$PN"G14"99;
"PT31B"
$PN"F14"100;
"PT41A"
$PN"A18"97;
"PT41B"
$PN"B19"92;
"PT43A||R_GPLLT"
$PN"A20"83;
"PT43B||R_GPLLC"
$PN"B21"84;
%"Q_RES"
"1","(-2225,-875)","0","pure_quanta","I19";
;
PART_NUMBER"CS03322FB03"
MATERIAL"CHIP"
VALUE"33.2"
LOCATION"R3482"
CDS_LIB"pure_quanta"
WATTAGE"1/16W"
PACK_TYPE"0402LF"
TOLERANCE"1%"
$SEC"1"
CDS_SEC"1";
"B"
$PN"2"141;
"A"
$PN"1"23;
%"Q_RES"
"1","(-2225,100)","0","pure_quanta","I197";
;
PART_NUMBER"CS03322FB03"
VALUE"33.2"
MATERIAL"CHIP"
LOCATION"R4714"
CDS_LIB"pure_quanta"
TOLERANCE"1%"
PACK_TYPE"0402LF"
WATTAGE"1/16W"
$SEC"1"
CDS_SEC"1";
"B"
$PN"2"11;
"A"
$PN"1"14;
%"Q_RES"
"1","(-2225,25)","0","pure_quanta","I198";
;
PART_NUMBER"CS03322FB03"
VALUE"33.2"
MATERIAL"CHIP"
LOCATION"R4715"
WATTAGE"1/16W"
PACK_TYPE"0402LF"
TOLERANCE"1%"
CDS_LIB"pure_quanta"
$SEC"1"
CDS_SEC"1";
"B"
$PN"2"9;
"A"
$PN"1"13;
%"Q_RES"
"1","(-2225,-1000)","0","pure_quanta","I20";
;
PART_NUMBER"CS03322FB03"
MATERIAL"CHIP"
VALUE"33.2"
LOCATION"R3483"
CDS_LIB"pure_quanta"
WATTAGE"1/16W"
PACK_TYPE"0402LF"
TOLERANCE"1%"
$SEC"1"
CDS_SEC"1";
"B"
$PN"2"142;
"A"
$PN"1"134;
%"Q_RES"
"1","(-2225,-625)","0","pure_quanta","I21";
;
PART_NUMBER"CS03322FB03"
VALUE"33.2"
MATERIAL"CHIP"
LOCATION"R3480"
CDS_LIB"pure_quanta"
WATTAGE"1/16W"
PACK_TYPE"0402LF"
TOLERANCE"1%"
$SEC"1"
CDS_SEC"1";
"B"
$PN"2"135;
"A"
$PN"1"21;
%"Q_RES"
"1","(-2225,-750)","0","pure_quanta","I22";
;
PART_NUMBER"CS03322FB03"
MATERIAL"CHIP"
VALUE"33.2"
LOCATION"R3481"
CDS_LIB"pure_quanta"
WATTAGE"1/16W"
PACK_TYPE"0402LF"
TOLERANCE"1%"
$SEC"1"
CDS_SEC"1";
"B"
$PN"2"140;
"A"
$PN"1"22;
%"Q_RES"
"1","(-2225,-375)","0","pure_quanta","I23";
;
PART_NUMBER"CS03322FB03"
VALUE"33.2"
MATERIAL"CHIP"
LOCATION"R3478"
TOLERANCE"1%"
PACK_TYPE"0402LF"
WATTAGE"1/16W"
CDS_LIB"pure_quanta"
$SEC"1"
CDS_SEC"1";
"B"
$PN"2"10;
"A"
$PN"1"19;
%"Q_RES"
"1","(-2225,-500)","0","pure_quanta","I24";
;
PART_NUMBER"CS03322FB03"
MATERIAL"CHIP"
VALUE"33.2"
LOCATION"R3479"
CDS_LIB"pure_quanta"
WATTAGE"1/16W"
PACK_TYPE"0402LF"
TOLERANCE"1%"
$SEC"1"
CDS_SEC"1";
"B"
$PN"2"17;
"A"
$PN"1"20;
%"Q_RES"
"1","(-2225,-125)","0","pure_quanta","I25";
;
PART_NUMBER"CS03322FB03"
VALUE"33.2"
MATERIAL"CHIP"
LOCATION"R3476"
CDS_LIB"pure_quanta"
WATTAGE"1/16W"
PACK_TYPE"0402LF"
TOLERANCE"1%"
$SEC"1"
CDS_SEC"1";
"B"
$PN"2"15;
"A"
$PN"1"16;
%"Q_RES"
"1","(-2225,-250)","0","pure_quanta","I26";
;
PART_NUMBER"CS03322FB03"
VALUE"33.2"
MATERIAL"CHIP"
LOCATION"R3477"
CDS_LIB"pure_quanta"
WATTAGE"1/16W"
PACK_TYPE"0402LF"
TOLERANCE"1%"
$SEC"1"
CDS_SEC"1";
"B"
$PN"2"8;
"A"
$PN"1"18;
%"Q_RES"
"2","(-3375,850)","0","pure_quanta","I41";
;
PART_NUMBER"CS31002FB08"
VALUE"10K"
MATERIAL"EMPTY"
WATTAGE"1/16W"
TOLERANCE"1%"
PACK_TYPE"0402LF"
$LOCATION"R2343"
CDS_LIB"pure_quanta"
CDS_LOCATION"R2343"
$SEC"1"
CDS_SEC"1";
"A"
$PN"1"1;
"B"
$PN"2"12;
%"UNIVERSAL_POWER"
"1","(-3375,1100)","0","logical_power","I42";
;
HDL_POWER"P5V_AUX_VCC"
CDS_LIB"logical_power";
"A"1;
%"MOSFET_NCH_DUAL"
"1","(-2450,525)","0","pure_quanta","I43";
;
PART_NUMBER"BAM138K0003"
MATERIAL"IC"
PART_TYPE"SMLF"
VALUE"PJT138K"
LOCATION"Q50"
CDS_LIB"pure_quanta"
CDS_LMAN_SYM_OUTLINE"-150,150,150,-150"
NEEDS_NO_SIZE"TRUE"
$SEC"1"
CDS_SEC"1";
"D1"
$PN"6"24;
"G1"
$PN"2"12;
"S1"
$PN"1"7;
%"UNIVERSAL_GND"
"1","(-2400,225)","0","logical_power","I44";
;
CDS_LIB"logical_power"
HDL_POWER"GND";
"A"7;
%"Q_RES"
"2","(-2400,1050)","0","pure_quanta","I45";
;
PART_NUMBER"CS24702JB10"
PACK_TYPE"0402LF"
VALUE"4.7K"
MATERIAL"CHIP"
WATTAGE"1/16W"
TOLERANCE"5%"
$LOCATION"R2344"
CDS_LIB"pure_quanta"
CDS_LOCATION"R2344"
$SEC"1"
CDS_SEC"1";
"A"
$PN"1"4;
"B"
$PN"2"24;
%"UNIVERSAL_POWER"
"1","(-2400,1300)","0","logical_power","I46";
;
HDL_POWER"P3V3_AUX"
CDS_LIB"logical_power";
"A"4;
%"Q_RES"
"2","(-2300,2625)","2","pure_quanta","I47";
;
PART_NUMBER"CS31002FB08"
WATTAGE"1/16W"
PACK_TYPE"0402LF"
TOLERANCE"1%"
VALUE"10K"
MATERIAL"CHIP"
$LOCATION"R1681"
CDS_LIB"pure_quanta"
CDS_LOCATION"R1681"
$SEC"1"
CDS_SEC"1";
"A"
$PN"1"3;
"B"
$PN"2"152;
%"UNIVERSAL_POWER"
"1","(-2300,2900)","0","logical_power","I48";
;
HDL_POWER"P3V3_AUX"
CDS_LIB"logical_power";
"A"3;
%"MOSFET_NCH_DUAL"
"2","(-1300,525)","0","pure_quanta","I49";
;
PART_NUMBER"BAM138K0003"
PART_TYPE"SMLF"
VALUE"PJT138K"
MATERIAL"IC"
LOCATION"Q50"
CDS_LIB"pure_quanta"
CDS_LMAN_SYM_OUTLINE"-150,150,150,-150"
NEEDS_NO_SIZE"TRUE"
$SEC"2"
CDS_SEC"2";
"S2"
$PN"4"6;
"G2"
$PN"5"24;
"D2"
$PN"3"25;
%"UNIVERSAL_GND"
"1","(-1250,225)","0","logical_power","I50";
;
CDS_LIB"logical_power"
HDL_POWER"GND";
"A"6;
%"Q_RES"
"2","(-1250,1050)","0","pure_quanta","I51";
;
PART_NUMBER"CS24702JB10"
PACK_TYPE"0402LF"
MATERIAL"CHIP"
WATTAGE"1/16W"
TOLERANCE"5%"
VALUE"4.7K"
$LOCATION"R2346"
CDS_LIB"pure_quanta"
CDS_LOCATION"R2346"
$SEC"1"
CDS_SEC"1";
"A"
$PN"1"5;
"B"
$PN"2"25;
%"UNIVERSAL_POWER"
"1","(-1250,1300)","0","logical_power","I52";
;
HDL_POWER"P3V3_AUX"
CDS_LIB"logical_power";
"A"5;
END.
